# S9S_MB_2U (Grand Teton) — schematic parts with pin connectivity, parts 1608–1608 of 6093; source: Cadence DE-HDL packaged netlist (pstxprt.dat, pstxnet.dat, pstchip.dat)

J15  SCONN288_ADR50017P130CC  SCONN288_ADR50017-P130CC IO  pkg DDR288S_1-1VXB  page 96
  1  VIN_BULK0  POWER  = P12V_S3_AUX_CPU0_NVDIMM
  2  RFU0  TRI  = TP_CHH_CPU0_DIMM1_FRU_0
  3  VIN_MGMT  POWER  = P3V3_AUX
  4  HSCL  IN  = I3C_SPD_DDREFGH_CPU0_LVC1_SCL_6
  5  HSDA  BI  = I3C_SPD_DDREFGH_CPU0_LVC1_SDA
  6  VSS0  POWER  = GND
  7  DQ0_A  BI  = M_H_CPU0_SA_DQ<0>
  8  VSS1  POWER  = GND
  9  DQ1_A  BI  = M_H_CPU0_SA_DQ<1>
  10  VSS2  POWER  = GND
  11  DQS0_A_T  BI  = M_H_CPU0_SA_DQS_DP<0>
  12  DQS0_A_C  BI  = M_H_CPU0_SA_DQS_DN<0>
  13  VSS3  POWER  = GND
  14  DQ4_A  BI  = M_H_CPU0_SA_DQ<4>
  15  VSS4  POWER  = GND
  16  DQ5_A  BI  = M_H_CPU0_SA_DQ<5>
  17  VSS5  POWER  = GND
  18  DQ8_A  BI  = M_H_CPU0_SA_DQ<8>
  19  VSS6  POWER  = GND
  20  DQ9_A  BI  = M_H_CPU0_SA_DQ<9>
  21  VSS7  POWER  = GND
  22  DQS1_A_T  BI  = M_H_CPU0_SA_DQS_DP<1>
  23  DQS1_A_C  BI  = M_H_CPU0_SA_DQS_DN<1>
  24  VSS8  POWER  = GND
  25  DQ12_A  BI  = M_H_CPU0_SA_DQ<12>
  26  VSS9  POWER  = GND
  27  DQ13_A  BI  = M_H_CPU0_SA_DQ<13>
  28  VSS10  POWER  = GND
  29  DQ16_A  BI  = M_H_CPU0_SA_DQ<16>
  30  VSS11  POWER  = GND
  31  DQ17_A  BI  = M_H_CPU0_SA_DQ<17>
  32  VSS12  POWER  = GND
  33  DQS2_A_T  BI  = M_H_CPU0_SA_DQS_DP<2>
  34  DQS2_A_C  BI  = M_H_CPU0_SA_DQS_DN<2>
  35  VSS13  POWER  = GND
  36  DQ20_A  BI  = M_H_CPU0_SA_DQ<20>
  37  VSS14  POWER  = GND
  38  DQ21_A  BI  = M_H_CPU0_SA_DQ<21>
  39  VSS15  POWER  = GND
  40  DQ24_A  BI  = M_H_CPU0_SA_DQ<24>
  41  VSS16  POWER  = GND
  42  DQ25_A  BI  = M_H_CPU0_SA_DQ<25>
  43  VSS17  POWER  = GND
  44  DQS3_A_T  BI  = M_H_CPU0_SA_DQS_DP<3>
  45  DQS3_A_C  BI  = M_H_CPU0_SA_DQS_DN<3>
  46  VSS18  POWER  = GND
  47  DQ28_A  BI  = M_H_CPU0_SA_DQ<28>
  48  VSS19  POWER  = GND
  49  DQ29_A  BI  = M_H_CPU0_SA_DQ<29>
  50  VSS20  POWER  = GND
  51  CB0_A  BI  = M_H_CPU0_SA_CB<0>
  52  VSS21  POWER  = GND
  53  CB1_A  BI  = M_H_CPU0_SA_CB<1>
  54  VSS22  POWER  = GND
  55  DQS4_A_T  BI  = M_H_CPU0_SA_DQS_DP<4>
  56  DQS4_A_C  BI  = M_H_CPU0_SA_DQS_DN<4>
  57  VSS23  POWER  = GND
  58  CB4_A  BI  = M_H_CPU0_SA_CB<4>
  59  VSS24  POWER  = GND
  60  CB5_A  BI  = M_H_CPU0_SA_CB<5>
  61  VSS25  POWER  = GND
  62  ALERT_N  OUT  = M_H_CPU0_ALERT_N
  63  VSS26  POWER  = GND
  64  CS0_A_N  IN  = M_H_CPU0_SA_CS_N<0>
  65  VSS27  POWER  = GND
  66  CA0_A  IN  = M_H_CPU0_SA_CA<0>
  67  VSS28  POWER  = GND
  68  CA2_A  IN  = M_H_CPU0_SA_CA<2>
  69  VSS29  POWER  = GND
  70  CA4_A  IN  = M_H_CPU0_SA_CA<4>
  71  VSS30  POWER  = GND
  72  CA6_A  IN  = M_H_CPU0_SA_CA<6>
  73  VSS31  POWER  = GND
  74  PAR_A  IN  = M_H_CPU0_SA_PAR
  75  VSS32  POWER  = GND
  76  CA0_B  IN  = M_H_CPU0_SB_CA<0>
  77  VSS33  POWER  = GND
  78  CA2_B  IN  = M_H_CPU0_SB_CA<2>
  79  VSS34  POWER  = GND
  80  CA4_B  IN  = M_H_CPU0_SB_CA<4>
  81  VSS35  POWER  = GND
  82  CA6_B  IN  = M_H_CPU0_SB_CA<6>
  83  VSS36  POWER  = GND
  84  CS0_B_N  IN  = M_H_CPU0_SB_CS_N<0>
  85  VSS37  POWER  = GND
  86  \lbd||rsp_a_n\  OUT  = M_H_CPU0_SA_RSP<0>
  87  \lbs||rsp_b_n\  OUT  = M_H_CPU0_SB_RSP<0>
  88  VSS38  POWER  = GND
  89  CB4_B  BI  = M_H_CPU0_SB_CB<4>
  90  VSS39  POWER  = GND
  91  CB5_B  BI  = M_H_CPU0_SB_CB<5>
  92  VSS40  POWER  = GND
  93  \dqs9_b_t||tdqs9_b_t||dbi4_b_n\  BI  = M_H_CPU0_SB_DQS_DP<9>
  94  \dqs9_b_c||tdqs9_b_c\  BI  = M_H_CPU0_SB_DQS_DN<9>
  95  VSS41  POWER  = GND
  96  CB0_B  BI  = M_H_CPU0_SB_CB<0>
  97  VSS42  POWER  = GND
  98  CB1_B  BI  = M_H_CPU0_SB_CB<1>
  99  VSS43  POWER  = GND
  100  DQ0_B  BI  = M_H_CPU0_SB_DQ<0>
  101  VSS44  POWER  = GND
  102  DQ1_B  BI  = M_H_CPU0_SB_DQ<1>
  103  VSS45  POWER  = GND
  104  DQS0_B_T  BI  = M_H_CPU0_SB_DQS_DP<0>
  105  DQS0_B_C  BI  = M_H_CPU0_SB_DQS_DN<0>
  106  VSS46  POWER  = GND
  107  DQ4_B  BI  = M_H_CPU0_SB_DQ<4>
  108  VSS47  POWER  = GND
  109  DQ5_B  BI  = M_H_CPU0_SB_DQ<5>
  110  VSS48  POWER  = GND
  111  DQ8_B  BI  = M_H_CPU0_SB_DQ<8>
  112  VSS49  POWER  = GND
  113  DQ9_B  BI  = M_H_CPU0_SB_DQ<9>
  114  VSS50  POWER  = GND
  115  DQS1_B_T  BI  = M_H_CPU0_SB_DQS_DP<1>
  116  DQS1_B_C  BI  = M_H_CPU0_SB_DQS_DN<1>
  117  VSS51  POWER  = GND
  118  DQ12_B  BI  = M_H_CPU0_SB_DQ<12>
  119  VSS52  POWER  = GND
  120  DQ13_B  BI  = M_H_CPU0_SB_DQ<13>
  121  VSS53  POWER  = GND
  122  DQ16_B  BI  = M_H_CPU0_SB_DQ<16>
  123  VSS54  POWER  = GND
  124  DQ17_B  BI  = M_H_CPU0_SB_DQ<17>
  125  VSS55  POWER  = GND
  126  DQS2_B_T  BI  = M_H_CPU0_SB_DQS_DP<2>
  127  DQS2_B_C  BI  = M_H_CPU0_SB_DQS_DN<2>
  128  VSS56  POWER  = GND
  129  DQ20_B  BI  = M_H_CPU0_SB_DQ<20>
  130  VSS57  POWER  = GND
  131  DQ21_B  BI  = M_H_CPU0_SB_DQ<21>
  132  VSS58  POWER  = GND
  133  DQ24_B  BI  = M_H_CPU0_SB_DQ<24>
  134  VSS59  POWER  = GND
  135  DQ25_B  BI  = M_H_CPU0_SB_DQ<25>
  136  VSS60  POWER  = GND
  137  DQS3_B_T  BI  = M_H_CPU0_SB_DQS_DP<3>
  138  DQS3_B_C  BI  = M_H_CPU0_SB_DQS_DN<3>
  139  VSS61  POWER  = GND
  140  DQ28_B  BI  = M_H_CPU0_SB_DQ<28>
  141  VSS62  POWER  = GND
  142  DQ29_B  BI  = M_H_CPU0_SB_DQ<29>
  143  VSS63  POWER  = GND
  144  RFU1  TRI  = TP_CHH_CPU0_DIMM1_FRU_1
  145  VIN_BULK1  POWER  = P12V_S3_AUX_CPU0_NVDIMM
  146  VIN_BULK2  POWER  = P12V_S3_AUX_CPU0_NVDIMM
  147  \pwr_good||fail_n\  BI  = PWRGD_CHH_CPU0_DIMM1
  148  HSA  IN  = PD_CHH_CPU0_DIMM1_SAA
  149  RFU2  TRI  = TP_CHH_CPU0_DIMM1_FRU_2
  150  RFU3  TRI  = TP_CHH_CPU0_DIMM1_FRU_3
  151  VSS64  POWER  = GND
  152  DQ2_A  BI  = M_H_CPU0_SA_DQ<2>
  153  VSS65  POWER  = GND
  154  DQ3_A  BI  = M_H_CPU0_SA_DQ<3>
  155  VSS66  POWER  = GND
  156  \dqs5_a_c||tdqs5_a_c||dqs5_a_t||tdqs5_a_t\  BI  = M_H_CPU0_SA_DQS_DN<5>
  157  \dqs5_a_t||tdqs5_a_t\  BI  = M_H_CPU0_SA_DQS_DP<5>
  158  VSS67  POWER  = GND
  159  DQ6_A  BI  = M_H_CPU0_SA_DQ<6>
  160  VSS68  POWER  = GND
  161  DQ7_A  BI  = M_H_CPU0_SA_DQ<7>
  162  VSS69  POWER  = GND
  163  DQ10_A  BI  = M_H_CPU0_SA_DQ<10>
  164  VSS70  POWER  = GND
  165  DQ11_A  BI  = M_H_CPU0_SA_DQ<11>
  166  VSS71  POWER  = GND
  167  \dqs6_a_c||tdqs6_a_c||dqs6_a_t||tdqs6_a_t\  BI  = M_H_CPU0_SA_DQS_DN<6>
  168  \dqs6_a_t||tdqs6_a_t\  BI  = M_H_CPU0_SA_DQS_DP<6>
  169  VSS72  POWER  = GND
  170  DQ14_A  BI  = M_H_CPU0_SA_DQ<14>
  171  VSS73  POWER  = GND
  172  DQ15_A  BI  = M_H_CPU0_SA_DQ<15>
  173  VSS74  POWER  = GND
  174  DQ18_A  BI  = M_H_CPU0_SA_DQ<18>
  175  VSS75  POWER  = GND
  176  DQ19_A  BI  = M_H_CPU0_SA_DQ<19>
  177  VSS76  POWER  = GND
  178  \dqs7_a_c||tdqs7_a_c\  BI  = M_H_CPU0_SA_DQS_DN<7>
  179  \dqs7_a_t||tdqs7_a_t\  BI  = M_H_CPU0_SA_DQS_DP<7>
  180  VSS77  POWER  = GND
  181  DQ22_A  BI  = M_H_CPU0_SA_DQ<22>
  182  VSS78  POWER  = GND
  183  DQ23_A  BI  = M_H_CPU0_SA_DQ<23>
  184  VSS79  POWER  = GND
  185  DQ26_A  BI  = M_H_CPU0_SA_DQ<26>
  186  VSS80  POWER  = GND
  187  DQ27_A  BI  = M_H_CPU0_SA_DQ<27>
  188  VSS81  POWER  = GND
  189  \dqs8_a_c||tdqs8_a_c\  BI  = M_H_CPU0_SA_DQS_DN<8>
  190  \dqs8_a_t||tdqs8_a_t\  BI  = M_H_CPU0_SA_DQS_DP<8>
  191  VSS82  POWER  = GND
  192  DQ30_A  BI  = M_H_CPU0_SA_DQ<30>
  193  VSS83  POWER  = GND
  194  DQ31_A  BI  = M_H_CPU0_SA_DQ<31>
  195  VSS84  POWER  = GND
  196  CB2_A  BI  = M_H_CPU0_SA_CB<2>
  197  VSS85  POWER  = GND
  198  CB3_A  BI  = M_H_CPU0_SA_CB<3>
  199  VSS86  POWER  = GND
  200  \dqs9_a_c||tdqs9_a_c\  BI  = M_H_CPU0_SA_DQS_DN<9>
  201  \dqs9_a_t||tdqs9_a_t\  BI  = M_H_CPU0_SA_DQS_DP<9>
  202  VSS87  POWER  = GND
  203  CB6_A  BI  = M_H_CPU0_SA_CB<6>
  204  VSS88  POWER  = GND
  205  CB7_A  BI  = M_H_CPU0_SA_CB<7>
  206  VSS89  POWER  = GND
  207  RESET_N  IN  = RST_M_GH_CPU0_FPGA_N
  208  VSS90  POWER  = GND
  209  CS1_A_N  IN  = M_H_CPU0_SA_CS_N<1>
  210  VSS91  POWER  = GND
  211  CA1_A  IN  = M_H_CPU0_SA_CA<1>
  212  VSS92  POWER  = GND
  213  CA3_A  IN  = M_H_CPU0_SA_CA<3>
  214  VSS93  POWER  = GND
  215  CA5_A  IN  = M_H_CPU0_SA_CA<5>
  216  VSS94  POWER  = GND
  217  CK_T  IN  = M_H_CPU0_CLK_DP<0>
  218  CK_C  IN  = M_H_CPU0_CLK_DN<0>
  219  VSS95  POWER  = GND
  220  RFU4  TRI  = TP_CHH_CPU0_DIMM1_FRU_4
  221  CA1_B  IN  = M_H_CPU0_SB_CA<1>
  222  VSS96  POWER  = GND
  223  CA3_B  IN  = M_H_CPU0_SB_CA<3>
  224  VSS97  POWER  = GND
  225  CA5_B  IN  = M_H_CPU0_SB_CA<5>
  226  VSS98  POWER  = GND
  227  PAR_B  IN  = M_H_CPU0_SB_PAR
  228  VSS99  POWER  = GND
  229  CS1_B_N  IN  = M_H_CPU0_SB_CS_N<1>
  230  VSS100  POWER  = GND
  231  RFU5  TRI  = TP_CHH_CPU0_DIMM1_FRU_5
  232  RFU6  TRI  = TP_CHH_CPU0_DIMM1_FRU_6
  233  VSS101  POWER  = GND
  234  CB6_B  BI  = M_H_CPU0_SB_CB<6>
  235  VSS102  POWER  = GND
  236  CB7_B  BI  = M_H_CPU0_SB_CB<7>
  237  VSS103  POWER  = GND
  238  DQS4_B_C  BI  = M_H_CPU0_SB_DQS_DN<4>
  239  DQS4_B_T  BI  = M_H_CPU0_SB_DQS_DP<4>
  240  VSS104  POWER  = GND
  241  CB2_B  BI  = M_H_CPU0_SB_CB<2>
  242  VSS105  POWER  = GND
  243  CB3_B  BI  = M_H_CPU0_SB_CB<3>
  244  VSS106  POWER  = GND
  245  DQ2_B  BI  = M_H_CPU0_SB_DQ<2>
  246  VSS107  POWER  = GND
  247  DQ3_B  BI  = M_H_CPU0_SB_DQ<3>
  248  VSS108  POWER  = GND
  249  \dqs5_b_c||tdqs5_b_c\  BI  = M_H_CPU0_SB_DQS_DN<5>
  250  \dqs5_b_t||tdqs5_b_t\  BI  = M_H_CPU0_SB_DQS_DP<5>
  251  VSS109  POWER  = GND
  252  DQ6_B  BI  = M_H_CPU0_SB_DQ<6>
  253  VSS110  POWER  = GND
  254  DQ7_B  BI  = M_H_CPU0_SB_DQ<7>
  255  VSS111  POWER  = GND
  256  DQ10_B  BI  = M_H_CPU0_SB_DQ<10>
  257  VSS112  POWER  = GND
  258  DQ11_B  BI  = M_H_CPU0_SB_DQ<11>
  259  VSS113  POWER  = GND
  260  \dqs6_b_c||tdqs6_b_c\  BI  = M_H_CPU0_SB_DQS_DN<6>
  261  \dqs6_b_t||tdqs6_b_t\  BI  = M_H_CPU0_SB_DQS_DP<6>
  262  VSS114  POWER  = GND
  263  DQ14_B  BI  = M_H_CPU0_SB_DQ<14>
  264  VSS115  POWER  = GND
  265  DQ15_B  BI  = M_H_CPU0_SB_DQ<15>
  266  VSS116  POWER  = GND
  267  DQ18_B  BI  = M_H_CPU0_SB_DQ<18>
  268  VSS117  POWER  = GND
  269  DQ19_B  BI  = M_H_CPU0_SB_DQ<19>
  270  VSS118  POWER  = GND
  271  \dqs7_b_c||tdqs7_b_c\  BI  = M_H_CPU0_SB_DQS_DN<7>
  272  \dqs7_b_t||tdqs7_b_t\  BI  = M_H_CPU0_SB_DQS_DP<7>
  273  VSS119  POWER  = GND
  274  DQ22_B  BI  = M_H_CPU0_SB_DQ<22>
  275  VSS120  POWER  = GND
  276  DQ23_B  BI  = M_H_CPU0_SB_DQ<23>
  277  VSS121  POWER  = GND
  278  DQ26_B  BI  = M_H_CPU0_SB_DQ<26>
  279  VSS122  POWER  = GND
  280  DQ27_B  BI  = M_H_CPU0_SB_DQ<27>
  281  VSS123  POWER  = GND
  282  \dqs8_b_c||tdqs8_b_c\  BI  = M_H_CPU0_SB_DQS_DN<8>
  283  \dqs8_b_t||tdqs8_b_t\  BI  = M_H_CPU0_SB_DQS_DP<8>
  284  VSS124  POWER  = GND
  285  DQ30_B  BI  = M_H_CPU0_SB_DQ<30>
  286  VSS125  POWER  = GND
  287  DQ31_B  BI  = M_H_CPU0_SB_DQ<31>
  288  VSS126  POWER  = GND
  G1  G1  POWER  = GND
  G2  G2  POWER  = GND
  G3  G3  POWER  = GND
